# S9S_MB_2U (Grand Teton) — schematic netlist excerpt (pin names and nets, part order shuffled) for the footprints in the layout excerpt that follows; sources: Cadence DE-HDL packaged netlist, KiCad conversion of 03242023_DA0F0TMBIJ0_F0T_Motherboard_J_brd_V01_OCP.brd

C1314  Q_CAP  10UF 6.3V 20% X6S  pkg C0603  page 210 : A = P3V3_AUX_CLK_GEN_VDDPT_CK440 ; B = GND
C2445  Q_CAP  1000PF 50V 5% EMPTY  pkg 0402  page 299 : A = FM_PVPP_HBM_CPU1_EN ; B = GND
C504  Q_CAP  47UF 4V 20% X6S  pkg C0805  page 76 : A = PVCCFA_EHV_CPU0 ; B = GND

(kicad_pcb
	(version 20260206)
	(generator "pcbnew")
	(generator_version "10.0")
	(general
		(thickness 1.6)
		(legacy_teardrops no)
	)
	(paper "A4")
	(title_block
		(title "03242023_DA0F0TMBIJ0_F0T_Motherboard_J_brd_V01_OCP.brd")
		(comment 1 "Grand Teton / footprints 4302-4304 of 6105")
	)
	(layers
		(0 "F.Cu" signal "TOP")
		(4 "In1.Cu" signal "GND")
		(6 "In2.Cu" signal "IN1")
		(8 "In3.Cu" signal "GND1")
		(10 "In4.Cu" signal "IN2")
		(12 "In5.Cu" signal "GND2")
		(14 "In6.Cu" signal "IN3")
		(16 "In7.Cu" signal "GND3")
		(18 "In8.Cu" signal "VCC")
		(20 "In9.Cu" signal "VCC1")
		(22 "In10.Cu" signal "GND4")
		(24 "In11.Cu" signal "IN4")
		(26 "In12.Cu" signal "GND5")
		(28 "In13.Cu" signal "IN5")
		(30 "In14.Cu" signal "GND6")
		(32 "In15.Cu" signal "IN6")
		(34 "In16.Cu" signal "GND7")
		(2 "B.Cu" signal "BOTTOM")
		(9 "F.Adhes" user "F.Adhesive")
		(11 "B.Adhes" user "B.Adhesive")
		(13 "F.Paste" user "Package Geometry/Pastemask Top")
		(15 "B.Paste" user "Package Geometry/Pastemask Bottom")
		(5 "F.SilkS" user "Ref Des/Silkscreen Top")
		(7 "B.SilkS" user "Ref Des/Silkscreen Bottom")
		(1 "F.Mask" user "Board Geometry/Soldermask Top")
		(3 "B.Mask" user "Board Geometry/Soldermask Bottom")
		(17 "Dwgs.User" user "User.Drawings")
		(19 "Cmts.User" user "User.Comments")
		(21 "Eco1.User" user "User.Eco1")
		(23 "Eco2.User" user "User.Eco2")
		(25 "Edge.Cuts" user "Board Geometry/Outline")
		(27 "Margin" user)
		(31 "F.CrtYd" user "Package Geometry/Place Bound Top")
		(29 "B.CrtYd" user "Package Geometry/Place Bound Bottom")
		(35 "F.Fab" user "Ref Des/Assembly Top")
		(33 "B.Fab" user "Ref Des/Assembly Bottom")
	)
	(footprint ""
		(layer "B.Cu")
		(at 121.782078 -355.194108)
		(property "Reference" "C2445"
			(at 0 0 0)
			(layer "B.SilkS")
			(hide yes)
			(effects
				(font
					(size 1.27 1.27)
				)
				(justify mirror)
			)
		)
		(property "Value" ""
			(at 0 0 0)
			(layer "B.Fab")
			(effects
				(font
					(size 1.27 1.27)
				)
				(justify mirror)
			)
		)
		(duplicate_pad_numbers_are_jumpers no)
		(fp_line
			(start -0.7874 -0.4064)
			(end -0.7874 0.4064)
			(stroke
				(width 0.1524)
				(type default)
			)
			(layer "B.SilkS")
		)
		(fp_line
			(start -0.7874 0.4064)
			(end 0.7874 0.4064)
			(stroke
				(width 0.1524)
				(type default)
			)
			(layer "B.SilkS")
		)
		(fp_line
			(start 0.7874 -0.4064)
			(end -0.7874 -0.4064)
			(stroke
				(width 0.1524)
				(type default)
			)
			(layer "B.SilkS")
		)
		(fp_line
			(start 0.7874 0.4064)
			(end 0.7874 -0.4064)
			(stroke
				(width 0.1524)
				(type default)
			)
			(layer "B.SilkS")
		)
		(fp_line
			(start -0.67945 -0.3048)
			(end -0.67945 0.3048)
			(stroke
				(width 0.1)
				(type default)
			)
			(layer "B.Fab")
		)
		(fp_line
			(start -0.67945 0.3048)
			(end -0.120396 0.3048)
			(stroke
				(width 0.1)
				(type default)
			)
			(layer "B.Fab")
		)
		(fp_line
			(start -0.12065 -0.3048)
			(end -0.67945 -0.3048)
			(stroke
				(width 0.1)
				(type default)
			)
			(layer "B.Fab")
		)
		(fp_line
			(start -0.12065 -0.2794)
			(end -0.12065 -0.3048)
			(stroke
				(width 0.1)
				(type default)
			)
			(layer "B.Fab")
		)
		(fp_line
			(start -0.120396 0.2794)
			(end 0.12065 0.2794)
			(stroke
				(width 0.1)
				(type default)
			)
			(layer "B.Fab")
		)
		(fp_line
			(start -0.120396 0.3048)
			(end -0.120396 0.2794)
			(stroke
				(width 0.1)
				(type default)
			)
			(layer "B.Fab")
		)
		(fp_line
			(start 0.12065 -0.305054)
			(end 0.12065 -0.2794)
			(stroke
				(width 0.1)
				(type default)
			)
			(layer "B.Fab")
		)
		(fp_line
			(start 0.12065 -0.2794)
			(end -0.12065 -0.2794)
			(stroke
				(width 0.1)
				(type default)
			)
			(layer "B.Fab")
		)
		(fp_line
			(start 0.12065 0.2794)
			(end 0.12065 0.3048)
			(stroke
				(width 0.1)
				(type default)
			)
			(layer "B.Fab")
		)
		(fp_line
			(start 0.12065 0.3048)
			(end 0.67945 0.3048)
			(stroke
				(width 0.1)
				(type default)
			)
			(layer "B.Fab")
		)
		(fp_line
			(start 0.67945 -0.305054)
			(end 0.12065 -0.305054)
			(stroke
				(width 0.1)
				(type default)
			)
			(layer "B.Fab")
		)
		(fp_line
			(start 0.67945 0.3048)
			(end 0.67945 -0.305054)
			(stroke
				(width 0.1)
				(type default)
			)
			(layer "B.Fab")
		)
		(pad "1" smd circle
			(at 0.40005 0 180)
			(size 0 0)
			(layers "B.Cu" "B.Mask" "B.Paste")
			(net "FM_PVPP_HBM_CPU1_EN")
		)
		(pad "2" smd circle
			(at -0.40005 0 180)
			(size 0 0)
			(layers "B.Cu" "B.Mask" "B.Paste")
			(net "GND")
		)
	)
	(footprint ""
		(layer "B.Cu")
		(at 355.826822 -212.049614 180)
		(property "Reference" "C504"
			(at 0 0 0)
			(layer "B.SilkS")
			(hide yes)
			(effects
				(font
					(size 1.27 1.27)
				)
				(justify mirror)
			)
		)
		(property "Value" ""
			(at 0 0 0)
			(layer "B.Fab")
			(effects
				(font
					(size 1.27 1.27)
				)
				(justify mirror)
			)
		)
		(duplicate_pad_numbers_are_jumpers no)
		(fp_line
			(start 1.524 0.762)
			(end 1.524 -0.762)
			(stroke
				(width 0.1524)
				(type default)
			)
			(layer "B.SilkS")
		)
		(fp_line
			(start 1.524 -0.762)
			(end -1.524 -0.762)
			(stroke
				(width 0.1524)
				(type default)
			)
			(layer "B.SilkS")
		)
		(fp_line
			(start -1.524 0.762)
			(end 1.524 0.762)
			(stroke
				(width 0.1524)
				(type default)
			)
			(layer "B.SilkS")
		)
		(fp_line
			(start -1.524 -0.762)
			(end -1.524 0.762)
			(stroke
				(width 0.1524)
				(type default)
			)
			(layer "B.SilkS")
		)
		(fp_line
			(start 1.1049 0.724916)
			(end -1.1049 0.724916)
			(stroke
				(width 0.1)
				(type default)
			)
			(layer "B.Fab")
		)
		(fp_line
			(start 1.1049 -0.724916)
			(end 1.1049 0.724916)
			(stroke
				(width 0.1)
				(type default)
			)
			(layer "B.Fab")
		)
		(fp_line
			(start -1.1049 0.724916)
			(end -1.1049 -0.724916)
			(stroke
				(width 0.1)
				(type default)
			)
			(layer "B.Fab")
		)
		(fp_line
			(start -1.1049 -0.724916)
			(end 1.1049 -0.724916)
			(stroke
				(width 0.1)
				(type default)
			)
			(layer "B.Fab")
		)
		(pad "1" smd rect
			(at 0.889 0 180)
			(size 1.016 1.27)
			(layers "B.Cu" "B.Mask" "B.Paste")
			(net "PVCCFA_EHV_CPU0")
		)
		(pad "2" smd rect
			(at -0.889 0 180)
			(size 1.016 1.27)
			(layers "B.Cu" "B.Mask" "B.Paste")
			(net "GND")
		)
	)
	(footprint ""
		(layer "B.Cu")
		(at 262.1026 -107.039918 -90)
		(property "Reference" "C1314"
			(at 0 0 90)
			(layer "B.SilkS")
			(hide yes)
			(effects
				(font
					(size 1.27 1.27)
				)
				(justify mirror)
			)
		)
		(property "Value" ""
			(at 0 0 90)
			(layer "B.Fab")
			(effects
				(font
					(size 1.27 1.27)
				)
				(justify mirror)
			)
		)
		(duplicate_pad_numbers_are_jumpers no)
		(fp_line
			(start -1.2954 0.5842)
			(end 1.2954 0.5842)
			(stroke
				(width 0.1524)
				(type default)
			)
			(layer "B.SilkS")
		)
		(fp_line
			(start 1.2954 0.5842)
			(end 1.2954 -0.5842)
			(stroke
				(width 0.1524)
				(type default)
			)
			(layer "B.SilkS")
		)
		(fp_line
			(start -1.2954 -0.5842)
			(end -1.2954 0.5842)
			(stroke
				(width 0.1524)
				(type default)
			)
			(layer "B.SilkS")
		)
		(fp_line
			(start 0 -0.5842)
			(end 0 0.5842)
			(stroke
				(width 0.1524)
				(type default)
			)
			(layer "B.SilkS")
		)
		(fp_line
			(start 1.2954 -0.5842)
			(end -1.2954 -0.5842)
			(stroke
				(width 0.1524)
				(type default)
			)
			(layer "B.SilkS")
		)
		(fp_line
			(start -0.8636 0.4572)
			(end 0.8636 0.4572)
			(stroke
				(width 0.1)
				(type default)
			)
			(layer "B.Fab")
		)
		(fp_line
			(start 0.8636 0.4572)
			(end 0.8636 0.4064)
			(stroke
				(width 0.1)
				(type default)
			)
			(layer "B.Fab")
		)
		(fp_line
			(start -1.1938 0.4064)
			(end -0.8636 0.4064)
			(stroke
				(width 0.1)
				(type default)
			)
			(layer "B.Fab")
		)
		(fp_line
			(start -0.8636 0.4064)
			(end -0.8636 0.4572)
			(stroke
				(width 0.1)
				(type default)
			)
			(layer "B.Fab")
		)
		(fp_line
			(start 0.8636 0.4064)
			(end 1.1938 0.4064)
			(stroke
				(width 0.1)
				(type default)
			)
			(layer "B.Fab")
		)
		(fp_line
			(start 1.1938 0.4064)
			(end 1.1938 -0.4064)
			(stroke
				(width 0.1)
				(type default)
			)
			(layer "B.Fab")
		)
		(fp_line
			(start -1.1938 -0.4064)
			(end -1.1938 0.4064)
			(stroke
				(width 0.1)
				(type default)
			)
			(layer "B.Fab")
		)
		(fp_line
			(start -0.8636 -0.4064)
			(end -1.1938 -0.4064)
			(stroke
				(width 0.1)
				(type default)
			)
			(layer "B.Fab")
		)
		(fp_line
			(start 0.8636 -0.4064)
			(end 0.8636 -0.4572)
			(stroke
				(width 0.1)
				(type default)
			)
			(layer "B.Fab")
		)
		(fp_line
			(start 1.1938 -0.4064)
			(end 0.8636 -0.4064)
			(stroke
				(width 0.1)
				(type default)
			)
			(layer "B.Fab")
		)
		(fp_line
			(start -0.8636 -0.4572)
			(end -0.8636 -0.4064)
			(stroke
				(width 0.1)
				(type default)
			)
			(layer "B.Fab")
		)
		(fp_line
			(start 0.8636 -0.4572)
			(end -0.8636 -0.4572)
			(stroke
				(width 0.1)
				(type default)
			)
			(layer "B.Fab")
		)
		(pad "1" smd rect
			(at 0.7366 0 180)
			(size 0.7112 0.8128)
			(layers "B.Cu" "B.Mask" "B.Paste")
			(net "P3V3_AUX_CLK_GEN_VDDPT_CK440")
		)
		(pad "2" smd rect
			(at -0.7366 0 180)
			(size 0.7112 0.8128)
			(layers "B.Cu" "B.Mask" "B.Paste")
			(net "GND")
		)
	)
)
